FILE_TYPE = CONNECTIVITY;
{Allegro Design Entry HDL 16.6-p007 (v16-6-112F) 10/10/2012}
"PAGE_NUMBER" = 228;
0"NC";
1"PVDDQ_KLM\g";
2"GND\g";
3"VR_FET_SW_P12V_STBY_PVDDQ_KLM\g";
4"GND\g";
5"P12V_STBY\g";
6"GND\g";
7"PVDDQ_KLM\g";
8"PVDDQ_KLM\g";
9"GND\g";
10"PVDDQ_KLM\g";
11"GND\g";
12"PVDDQ_KLM\g";
13"GND\g";
14"PVDDQ_KLM\g";
15"GND\g";
16"PVDDQ_KLM\g";
17"GND\g";
18"GND\g";
19"PVDDQ_KLM\g";
20"GND\g";
21"PVDDQ_KLM\g";
22"GND\g";
23"PVDDQ_KLM\g";
24"PVDDQ_KLM\g";
25"GND\g";
26"PVDDQ_KLM\g";
27"GND\g";
28"VSENSE_PVDDQ_KLM_P";
29"VSENSE_PVDDQ_KLM_N";
%"PVDDQ_KLM"
"1","(2525,1700)","0","mstr_symbols","I109";
;
BOM_COST"MEM_VRD_PVDDQ_CD"
ROOM"VDDQ_KLM_PWR_VR"
CDS_LIB"mstr_symbols"
VOLTAGE"1.2V"
BODY_TYPE"PLUMBING"
HDL_POWER"PVDDQ_KLM";
"G\NAC"1;
%"GND"
"1","(4250,1050)","0","mstr_symbols","I114";
;
VOLTAGE"0"
CDS_LIB"mstr_symbols"
SIZE"1B"
BOM_COST"MEM_VRD_PVDDQ_CD"
ROOM"VDDQ_KLM_PWR_VR"
BODY_TYPE"PLUMBING"
HDL_POWER"GND";
"A\NAC"2;
%"VCC_CORE"
"1","(-675,1350)","0","mstr_symbols","I120";
;
HDL_POWER"VR_FET_SW_P12V_STBY_PVDDQ_KLM"
CDS_LIB"mstr_symbols";
"A"3;
%"GND"
"1","(-675,675)","0","mstr_symbols","I123";
;
CDS_LIB"mstr_symbols"
SIZE"1B"
VOLTAGE"0"
BOM_COST"MEM_VRD_PVDDQ_CD"
ROOM"VDDQ_KLM_PWR_VR"
BODY_TYPE"PLUMBING"
HDL_POWER"GND";
"A\NAC"4;
%"CAPP"
"1","(-675,900)","0","mstr_discrete","I175";
;
CDS_SEC"1"
TOLERANCE"20%"
VOLTAGE"16V"
VALUE"270UF"
MATERIAL"OSCON"
PACK_TYPE"2626"
LOCATION"C1B10"
PART_NUMBER"A31228-047"
SEC_TYPE"2626"
SEC"1"
ROOM"VDDQ_KLM_PWR_VR"
CDS_LOCATION"C1B10"
CDS_LIB"mstr_discrete";
"B"
$PN"2"4;
"A"
$PN"1"3;
%"P12V_STBY"
"1","(-1400,1375)","0","mstr_symbols","I182";
;
SIZE"1B"
CDS_LIB"mstr_symbols"
VOLTAGE"12.0V"
BODY_TYPE"PLUMBING"
HDL_POWER"P12V_STBY";
"G\NAC"5;
%"GND"
"1","(-250,2625)","0","mstr_symbols","I189";
;
CDS_LIB"mstr_symbols"
VOLTAGE"0"
SIZE"1B"
BOM_COST"MEM_VRD_PVDDQ_CD"
ROOM"VDDQ_ABC_PWR_VR"
BODY_TYPE"PLUMBING"
HDL_POWER"GND";
"A\NAC"6;
%"PVDDQ_KLM"
"1","(-2325,3250)","0","mstr_symbols","I191";
;
ROOM"VDDQ_KLM_PWR_VR"
BOM_COST"MEM_VRD_PVPP_AB"
CDS_LIB"mstr_symbols"
VOLTAGE"1.2V"
BODY_TYPE"PLUMBING"
HDL_POWER"PVDDQ_KLM";
"G\NAC"7;
%"PVDDQ_KLM"
"1","(2550,1000)","0","mstr_symbols","I195";
;
ROOM"VDDQ_KLM_PWR_VR"
BOM_COST"MEM_VRD_PVDDQ_CD"
CDS_LIB"mstr_symbols"
VOLTAGE"1.2V"
BODY_TYPE"PLUMBING"
HDL_POWER"PVDDQ_KLM";
"G\NAC"8;
%"GND"
"1","(3300,325)","0","mstr_symbols","I197";
;
SIZE"1B"
CDS_LIB"mstr_symbols"
VOLTAGE"0"
ROOM"VDDQ_KLM_PWR_VR"
BOM_COST"MEM_VRD_PVDDQ_CD"
BODY_TYPE"PLUMBING"
HDL_POWER"GND";
"A\NAC"9;
%"CAP_A"
"1","(2550,725)","0","dev_discrete","I198";
;
PACK_TYPE"0603V"
VOLTAGE"4V"
PART_NUMBER"602433-106"
GROUP"PWR_MLCC_CAP"
TOLERANCE"20%"
MATERIAL"X5R"
VALUE"47UF"
LOCATION"C8M8"
BOM_SS"NOPOP"
SEC"1"
SEC_TYPE"0603V"
CDS_SEC"1"
CDS_LOCATION"C8M8"
CDS_LIB"dev_discrete";
"B"
$PN"2"9;
"A"
$PN"1"8;
%"CAP_A"
"1","(2900,725)","0","dev_discrete","I199";
;
BOM_SS"NOPOP"
PART_NUMBER"602433-106"
PACK_TYPE"0603V"
TOLERANCE"20%"
MATERIAL"X5R"
VOLTAGE"4V"
GROUP"PWR_MLCC_CAP"
VALUE"47UF"
LOCATION"C2A5"
CDS_LOCATION"C2A5"
CDS_SEC"1"
SEC_TYPE"0603V"
SEC"1"
CDS_LIB"dev_discrete";
"B"
$PN"2"9;
"A"
$PN"1"8;
%"CAP_A"
"1","(3300,725)","0","dev_discrete","I200";
;
TOLERANCE"20%"
VALUE"47UF"
LOCATION"C2B1"
PACK_TYPE"0603V"
PART_NUMBER"602433-106"
MATERIAL"X5R"
VOLTAGE"4V"
GROUP"PWR_MLCC_CAP"
BOM_SS"NOPOP"
SEC"1"
SEC_TYPE"0603V"
CDS_SEC"1"
CDS_LOCATION"C2B1"
CDS_LIB"dev_discrete";
"B"
$PN"2"9;
"A"
$PN"1"8;
%"CAP_A"
"1","(2525,1425)","0","dev_discrete","I201";
;
TOLERANCE"20%"
VALUE"47UF"
MATERIAL"X5R"
VOLTAGE"4V"
PART_NUMBER"602433-106"
BOM_SS"NOPOP"
LOCATION"C8L12"
GROUP"PWR_MLCC_CAP"
PACK_TYPE"0603V"
CDS_SEC"1"
SEC_TYPE"0603V"
SEC"1"
CDS_LOCATION"C8L12"
CDS_LIB"dev_discrete";
"B"
$PN"2"2;
"A"
$PN"1"1;
%"CAP_A"
"1","(2875,1425)","0","dev_discrete","I202";
;
PACK_TYPE"0603V"
VOLTAGE"4V"
TOLERANCE"20%"
LOCATION"C7M5"
MATERIAL"X5R"
VALUE"47UF"
PART_NUMBER"602433-106"
BOM_SS"NOPOP"
GROUP"PWR_MLCC_CAP"
CDS_SEC"1"
SEC_TYPE"0603V"
SEC"1"
CDS_LOCATION"C7M5"
CDS_LIB"dev_discrete";
"B"
$PN"2"2;
"A"
$PN"1"1;
%"CAP_A"
"1","(3275,1425)","0","dev_discrete","I203";
;
PART_NUMBER"602433-106"
PACK_TYPE"0603V"
GROUP"PWR_MLCC_CAP"
BOM_SS"078.1061T.M001"
MATERIAL"X5R"
TOLERANCE"20%"
VOLTAGE"4V"
VALUE"47UF"
LOCATION"C8M10"
SEC"1"
SEC_TYPE"0603V"
CDS_SEC"1"
CDS_LOCATION"C8M10"
CDS_LIB"dev_discrete";
"B"
$PN"2"2;
"A"
$PN"1"1;
%"CAP_A"
"1","(3625,1425)","0","dev_discrete","I204";
;
PACK_TYPE"0603V"
VOLTAGE"4V"
VALUE"47UF"
LOCATION"C2B2"
TOLERANCE"20%"
MATERIAL"X5R"
PART_NUMBER"602433-106"
BOM_SS"NOPOP"
GROUP"PWR_MLCC_CAP"
CDS_SEC"1"
SEC_TYPE"0603V"
SEC"1"
CDS_LOCATION"C2B2"
CDS_LIB"dev_discrete";
"B"
$PN"2"2;
"A"
$PN"1"1;
%"CAP_A"
"1","(3975,1425)","0","dev_discrete","I205";
;
LOCATION"C8M9"
TOLERANCE"20%"
VALUE"47UF"
VOLTAGE"4V"
MATERIAL"X5R"
BOM_SS"NOPOP"
GROUP"PWR_MLCC_CAP"
PACK_TYPE"0603V"
PART_NUMBER"602433-106"
CDS_SEC"1"
SEC_TYPE"0603V"
SEC"1"
CDS_LOCATION"C8M9"
CDS_LIB"dev_discrete";
"B"
$PN"2"2;
"A"
$PN"1"1;
%"CAP_A"
"1","(4375,1425)","0","dev_discrete","I206";
;
BOM_SS"NOPOP"
GROUP"PWR_MLCC_CAP"
PACK_TYPE"0603V"
MATERIAL"X5R"
VOLTAGE"4V"
TOLERANCE"20%"
LOCATION"C8M2"
VALUE"47UF"
PART_NUMBER"602433-106"
SEC"1"
SEC_TYPE"0603V"
CDS_SEC"1"
CDS_LOCATION"C8M2"
CDS_LIB"dev_discrete";
"B"
$PN"2"2;
"A"
$PN"1"1;
%"PVDDQ_KLM"
"1","(-1300,3250)","0","mstr_symbols","I207";
;
CDS_LIB"mstr_symbols"
VOLTAGE"1.2V"
ROOM"VDDQ_KLM_PWR_VR"
BOM_COST"MEM_VRD_PVPP_AB"
BODY_TYPE"PLUMBING"
HDL_POWER"PVDDQ_KLM";
"G\NAC"10;
%"GND"
"1","(-2325,2475)","0","mstr_symbols","I208";
;
HDL_POWER"GND"
BODY_TYPE"PLUMBING"
CDS_LIB"mstr_symbols"
VOLTAGE"0"
SIZE"1B"
BOM_COST"MEM_VRD_PVDDQ_CD"
ROOM"VDDQ_ABC_PWR_VR";
"A\NAC"11;
%"PVDDQ_KLM"
"1","(-2250,175)","0","mstr_symbols","I224";
;
ROOM"VDDQ_KLM_PWR_VR"
BOM_COST"VDDQ_KLM_PWR_VR"
VOLTAGE"1.2V"
CDS_LIB"mstr_symbols"
BODY_TYPE"PLUMBING"
HDL_POWER"PVDDQ_KLM";
"G\NAC"12;
%"GND"
"1","(-2250,-400)","0","mstr_symbols","I226";
;
BOM_COST"PROC_VRD_VCCIN_CPU0"
ROOM"VDDQ_ABC_PWR_VR"
CDS_LIB"mstr_symbols"
VOLTAGE"0"
SIZE"1B"
BODY_TYPE"PLUMBING"
HDL_POWER"GND";
"A\NAC"13;
%"PVDDQ_KLM"
"1","(-2225,-525)","0","mstr_symbols","I242";
;
BOM_COST"VDDQ_KLM_PWR_VR"
ROOM"VDDQ_KLM_PWR_VR"
CDS_LIB"mstr_symbols"
VOLTAGE"1.2V"
BODY_TYPE"PLUMBING"
HDL_POWER"PVDDQ_KLM";
"G\NAC"14;
%"GND"
"1","(-2225,-1075)","0","mstr_symbols","I244";
;
SIZE"1B"
VOLTAGE"0"
CDS_LIB"mstr_symbols"
BOM_COST"PROC_VRD_VCCIN_CPU0"
ROOM"VDDQ_ABC_PWR_VR"
BODY_TYPE"PLUMBING"
HDL_POWER"GND";
"A\NAC"15;
%"SHUNT"
"1","(75,2175)","0","mstr_misc","I245";
;
CDS_SEC"1"
CDS_LOCATION"SH7L2"
PART_NUMBER"N_A"
LOCATION"SH7L2"
SEC_TYPE"SH0201"
CDS_LIB"mstr_misc"
PACK_TYPE"SH0201"
PIN_SHORT"A:B"
SEC"1"
MATERIAL"EMPTY";
"A"
$PN"1"28;
"B"
$PN"2"23;
%"SHUNT"
"1","(75,1725)","0","mstr_misc","I246";
;
CDS_SEC"1"
CDS_LOCATION"SH7L1"
PART_NUMBER"N_A"
LOCATION"SH7L1"
SEC_TYPE"SH0201"
CDS_LIB"mstr_misc"
PACK_TYPE"SH0201"
PIN_SHORT"A:B"
SEC"1"
MATERIAL"EMPTY";
"A"
$PN"1"29;
"B"
$PN"2"22;
%"IND-100NH-35-GP"
"1","(-1050,1125)","1","w_hdl","I247";
;
CDS_SEC"1"
CDS_LOCATION"L1B1"
TYPE"IRMS=29A@DELTA_T<45C"
PACK_SIZE"DCR=0.16MOHM"
RATED"ISAT=16A@25C"
ATTRIBUTE"100NH"
LOCATION"L1B1"
VALUE"IND-100NH-35-GP"
PACK_TYPE"DISCRET-G8"
SEC"1"
SEC_TYPE"DISCRET-G8"
PART_NUMBER"068.1011N.M001"
CDS_LIB"w_hdl"
CDS_LMAN_SYM_OUTLINE"-75,100,75,-100";
"F"
$PN"2"3;
"S"
$PN"1"5;
%"PVDDQ_KLM"
"1","(650,3100)","0","mstr_symbols","I252";
;
HDL_POWER"PVDDQ_KLM"
BODY_TYPE"PLUMBING"
CDS_LIB"mstr_symbols"
ROOM"VDDQ_KLM_PWR_VR"
BOM_COST"MEM_VRD_PVPP_AB"
VOLTAGE"1.2V";
"G\NAC"16;
%"GND"
"1","(650,2325)","0","mstr_symbols","I253";
;
HDL_POWER"GND"
BODY_TYPE"PLUMBING"
ROOM"PVCCIN_CPU1_DECAP_VR"
SIZE"1B"
CDS_LIB"mstr_symbols"
VOLTAGE"0";
"A\NAC"17;
%"CAP_A"
"1","(1650,1800)","0","dev_discrete","I255";
;
TOLERANCE"20%"
MATERIAL"X6S"
LOCATION"C3D1"
VALUE"22.0UF"
PART_NUMBER"E15431-004"
PACK_TYPE"0603V"
GROUP"PWR_MLCC_CAP"
VOLTAGE"4V"
ROOM"PVCCIN_CPU1_DECAP_VR"
$SEC"1"
CDS_SEC"1"
CDS_LIB"dev_discrete"
BOM_COST"PROC"
CDS_LOCATION"C3D1";
"B"
$PN"2"18;
"A"
$PN"1"19;
%"CAP_A"
"1","(1300,1800)","0","dev_discrete","I256";
;
CDS_SEC"1"
TOLERANCE"20%"
MATERIAL"X6S"
VOLTAGE"4V"
LOCATION"C2D3"
VALUE"22.0UF"
PART_NUMBER"E15431-004"
PACK_TYPE"0603V"
GROUP"PWR_MLCC_CAP"
ROOM"PVCCIN_CPU1_DECAP_VR"
CDS_LIB"dev_discrete"
BOM_COST"PROC"
CDS_LOCATION"C2D3"
SEC_TYPE"0603V"
SEC"1";
"B"
$PN"2"18;
"A"
$PN"1"19;
%"CAP_A"
"1","(950,1800)","0","dev_discrete","I257";
;
CDS_SEC"1"
MATERIAL"X6S"
VOLTAGE"4V"
TOLERANCE"20%"
LOCATION"C2D2"
VALUE"22.0UF"
PART_NUMBER"E15431-004"
PACK_TYPE"0603V"
GROUP"PWR_MLCC_CAP"
ROOM"PVCCIN_CPU1_DECAP_VR"
CDS_LIB"dev_discrete"
BOM_COST"PROC"
CDS_LOCATION"C2D2"
SEC_TYPE"0603V"
SEC"1";
"B"
$PN"2"18;
"A"
$PN"1"19;
%"CAP_A"
"1","(600,1800)","0","dev_discrete","I258";
;
LOCATION"C2D1"
VOLTAGE"4V"
PACK_TYPE"0603V"
PART_NUMBER"E15431-004"
VALUE"22.0UF"
TOLERANCE"20%"
MATERIAL"X6S"
GROUP"PWR_MLCC_CAP"
CDS_LOCATION"C2D1"
BOM_COST"PROC"
CDS_LIB"dev_discrete"
CDS_SEC"1"
$SEC"1"
ROOM"PVCCIN_CPU1_DECAP_VR";
"B"
$PN"2"18;
"A"
$PN"1"19;
%"GND"
"1","(1650,1450)","0","mstr_symbols","I259";
;
ROOM"PVCCIN_CPU1_DECAP_VR"
SIZE"1B"
CDS_LIB"mstr_symbols"
VOLTAGE"0"
BODY_TYPE"PLUMBING"
HDL_POWER"GND";
"A\NAC"18;
%"PVDDQ_KLM"
"1","(600,2050)","0","mstr_symbols","I260";
;
VOLTAGE"1.2V"
BOM_COST"MEM_VRD_PVPP_AB"
ROOM"VDDQ_KLM_PWR_VR"
CDS_LIB"mstr_symbols"
BODY_TYPE"PLUMBING"
HDL_POWER"PVDDQ_KLM";
"G\NAC"19;
%"GND"
"1","(525,500)","0","mstr_symbols","I262";
;
VOLTAGE"0"
SIZE"1B"
CDS_LIB"mstr_symbols"
ROOM"PVCCIN_CPU1_DECAP_VR"
BODY_TYPE"PLUMBING"
HDL_POWER"GND";
"A\NAC"20;
%"PVDDQ_KLM"
"1","(525,950)","0","mstr_symbols","I263";
;
VOLTAGE"1.2V"
BOM_COST"MEM_VRD_PVPP_AB"
ROOM"VDDQ_KLM_PWR_VR"
CDS_LIB"mstr_symbols"
BODY_TYPE"PLUMBING"
HDL_POWER"PVDDQ_KLM";
"G\NAC"21;
%"CAP_A"
"1","(-1300,2975)","0","dev_discrete","I264";
;
GROUP"PWR_MLCC_CAP"
VOLTAGE"4V"
LOCATION"C2D7"
TOLERANCE"20%"
PACK_TYPE"0603V"
PART_NUMBER"E15431-004"
MATERIAL"X6S"
VALUE"22.0UF"
ROOM"PVCCIN_CPU0_DECAP_VR"
$SEC"1"
CDS_SEC"1"
CDS_LIB"dev_discrete"
BOM_COST"PROC_SOCKET"
CDS_LOCATION"C2D7";
"B"
$PN"2"6;
"A"
$PN"1"10;
%"CAP_A"
"1","(-950,2975)","0","dev_discrete","I265";
;
LOCATION"C2D4"
PACK_TYPE"0603V"
MATERIAL"X6S"
VOLTAGE"4V"
VALUE"22.0UF"
PART_NUMBER"E15431-004"
GROUP"PWR_MLCC_CAP"
TOLERANCE"20%"
ROOM"PVCCIN_CPU0_DECAP_VR"
$SEC"1"
CDS_SEC"1"
CDS_LIB"dev_discrete"
BOM_COST"PROC_SOCKET"
CDS_LOCATION"C2D4";
"B"
$PN"2"6;
"A"
$PN"1"10;
%"CAP_A"
"1","(-600,2975)","0","dev_discrete","I266";
;
VOLTAGE"4V"
TOLERANCE"20%"
PACK_TYPE"0603V"
MATERIAL"X6S"
PART_NUMBER"E15431-004"
LOCATION"C2D5"
VALUE"22.0UF"
GROUP"PWR_MLCC_CAP"
ROOM"PVCCIN_CPU0_DECAP_VR"
$SEC"1"
CDS_SEC"1"
CDS_LIB"dev_discrete"
BOM_COST"PROC_SOCKET"
CDS_LOCATION"C2D5";
"B"
$PN"2"6;
"A"
$PN"1"10;
%"CAP_A"
"1","(-250,2975)","0","dev_discrete","I267";
;
TOLERANCE"20%"
MATERIAL"X6S"
PART_NUMBER"E15431-004"
LOCATION"C2D6"
VOLTAGE"4V"
GROUP"PWR_MLCC_CAP"
VALUE"22.0UF"
PACK_TYPE"0603V"
ROOM"PVCCIN_CPU0_DECAP_VR"
$SEC"1"
CDS_SEC"1"
CDS_LIB"dev_discrete"
BOM_COST"PROC_SOCKET"
CDS_LOCATION"C2D6";
"B"
$PN"2"6;
"A"
$PN"1"10;
%"CAP_A"
"1","(-2250,-75)","0","dev_discrete","I268";
;
BOM_SS"E15431-004"
PACK_TYPE"0603V"
PART_NUMBER"602433-106"
GROUP"PWR_MLCC_CAP"
TOLERANCE"20%"
MATERIAL"X5R"
LOCATION"C7L5"
VOLTAGE"4V"
VALUE"47UF"
SEC_TYPE"0603V"
SEC"1"
CDS_LOCATION"C7L5"
CDS_SEC"1"
CDS_LIB"dev_discrete";
"B"
$PN"2"13;
"A"
$PN"1"12;
%"CAP_A"
"1","(-1950,-75)","0","dev_discrete","I269";
;
BOM_SS"E15431-004"
PACK_TYPE"0603V"
PART_NUMBER"602433-106"
GROUP"PWR_MLCC_CAP"
VALUE"47UF"
MATERIAL"X5R"
TOLERANCE"20%"
VOLTAGE"4V"
LOCATION"C3A6"
CDS_LIB"dev_discrete"
SEC"1"
SEC_TYPE"0603V"
CDS_SEC"1"
CDS_LOCATION"C3A6";
"B"
$PN"2"13;
"A"
$PN"1"12;
%"CAP_A"
"1","(-1650,-75)","0","dev_discrete","I270";
;
BOM_SS"E15431-004"
TOLERANCE"20%"
MATERIAL"X5R"
GROUP"PWR_MLCC_CAP"
VOLTAGE"4V"
VALUE"47UF"
LOCATION"C3A5"
PACK_TYPE"0603V"
PART_NUMBER"602433-106"
CDS_LIB"dev_discrete"
SEC"1"
SEC_TYPE"0603V"
CDS_SEC"1"
CDS_LOCATION"C3A5";
"B"
$PN"2"13;
"A"
$PN"1"12;
%"CAP_A"
"1","(-1375,-75)","0","dev_discrete","I271";
;
BOM_SS"E15431-004"
LOCATION"C2A15"
PART_NUMBER"602433-106"
PACK_TYPE"0603V"
MATERIAL"X5R"
VALUE"47UF"
TOLERANCE"20%"
VOLTAGE"4V"
GROUP"PWR_MLCC_CAP"
CDS_LIB"dev_discrete"
SEC"1"
SEC_TYPE"0603V"
CDS_SEC"1"
CDS_LOCATION"C2A15";
"B"
$PN"2"13;
"A"
$PN"1"12;
%"CAP_A"
"1","(-1100,-75)","0","dev_discrete","I272";
;
BOM_SS"E15431-004"
VOLTAGE"4V"
PACK_TYPE"0603V"
PART_NUMBER"602433-106"
MATERIAL"X5R"
TOLERANCE"20%"
VALUE"47UF"
LOCATION"C2A14"
GROUP"PWR_MLCC_CAP"
CDS_LIB"dev_discrete"
SEC"1"
SEC_TYPE"0603V"
CDS_SEC"1"
CDS_LOCATION"C2A14";
"B"
$PN"2"13;
"A"
$PN"1"12;
%"CAP_A"
"1","(-800,-75)","0","dev_discrete","I273";
;
BOM_SS"E15431-004"
MATERIAL"X5R"
VOLTAGE"4V"
TOLERANCE"20%"
PACK_TYPE"0603V"
PART_NUMBER"602433-106"
VALUE"47UF"
LOCATION"C2A6"
GROUP"PWR_MLCC_CAP"
CDS_SEC"1"
SEC_TYPE"0603V"
SEC"1"
CDS_LIB"dev_discrete"
CDS_LOCATION"C2A6";
"B"
$PN"2"13;
"A"
$PN"1"12;
%"CAP_A"
"1","(-500,-75)","0","dev_discrete","I274";
;
BOM_SS"E15431-004"
PACK_TYPE"0603V"
PART_NUMBER"602433-106"
VALUE"47UF"
MATERIAL"X5R"
VOLTAGE"4V"
TOLERANCE"20%"
LOCATION"C2A7"
GROUP"PWR_MLCC_CAP"
CDS_SEC"1"
SEC_TYPE"0603V"
SEC"1"
CDS_LIB"dev_discrete"
CDS_LOCATION"C2A7";
"B"
$PN"2"13;
"A"
$PN"1"12;
%"CAP_A"
"1","(-225,-75)","0","dev_discrete","I275";
;
BOM_SS"E15431-004"
PACK_TYPE"0603V"
VALUE"47UF"
MATERIAL"X5R"
LOCATION"C3A1"
VOLTAGE"4V"
TOLERANCE"20%"
PART_NUMBER"602433-106"
GROUP"PWR_MLCC_CAP"
CDS_SEC"1"
SEC_TYPE"0603V"
SEC"1"
CDS_LIB"dev_discrete"
CDS_LOCATION"C3A1";
"B"
$PN"2"13;
"A"
$PN"1"12;
%"CAP_A"
"1","(100,-75)","0","dev_discrete","I276";
;
BOM_SS"E15431-004"
VALUE"47UF"
PACK_TYPE"0603V"
LOCATION"C3A2"
VOLTAGE"4V"
TOLERANCE"20%"
MATERIAL"X5R"
PART_NUMBER"602433-106"
GROUP"PWR_MLCC_CAP"
CDS_SEC"1"
SEC_TYPE"0603V"
SEC"1"
CDS_LIB"dev_discrete"
CDS_LOCATION"C3A2";
"B"
$PN"2"13;
"A"
$PN"1"12;
%"CAP_A"
"1","(400,-75)","0","dev_discrete","I277";
;
BOM_SS"E15431-004"
VOLTAGE"4V"
PART_NUMBER"602433-106"
VALUE"47UF"
PACK_TYPE"0603V"
TOLERANCE"20%"
LOCATION"C2A9"
MATERIAL"X5R"
GROUP"PWR_MLCC_CAP"
CDS_SEC"1"
SEC_TYPE"0603V"
SEC"1"
CDS_LIB"dev_discrete"
CDS_LOCATION"C2A9";
"B"
$PN"2"13;
"A"
$PN"1"12;
%"CAP_A"
"1","(700,-75)","0","dev_discrete","I278";
;
BOM_SS"E15431-004"
PACK_TYPE"0603V"
LOCATION"C2A10"
VOLTAGE"4V"
VALUE"47UF"
TOLERANCE"20%"
PART_NUMBER"602433-106"
MATERIAL"X5R"
GROUP"PWR_MLCC_CAP"
CDS_SEC"1"
SEC_TYPE"0603V"
SEC"1"
CDS_LIB"dev_discrete"
CDS_LOCATION"C2A10";
"B"
$PN"2"13;
"A"
$PN"1"12;
%"CAP_A"
"1","(975,-75)","0","dev_discrete","I279";
;
BOM_SS"E15431-004"
PACK_TYPE"0603V"
MATERIAL"X5R"
LOCATION"C2A11"
VOLTAGE"4V"
VALUE"47UF"
TOLERANCE"20%"
PART_NUMBER"602433-106"
GROUP"PWR_MLCC_CAP"
CDS_SEC"1"
SEC_TYPE"0603V"
SEC"1"
CDS_LIB"dev_discrete"
CDS_LOCATION"C2A11";
"B"
$PN"2"13;
"A"
$PN"1"12;
%"CAP_A"
"1","(1250,-75)","0","dev_discrete","I280";
;
BOM_SS"E15431-004"
MATERIAL"X5R"
PART_NUMBER"602433-106"
LOCATION"C2A13"
TOLERANCE"20%"
VALUE"47UF"
VOLTAGE"4V"
PACK_TYPE"0603V"
GROUP"PWR_MLCC_CAP"
CDS_LIB"dev_discrete"
SEC"1"
SEC_TYPE"0603V"
CDS_SEC"1"
CDS_LOCATION"C2A13";
"B"
$PN"2"13;
"A"
$PN"1"12;
%"CAP_A"
"1","(1550,-75)","0","dev_discrete","I281";
;
BOM_SS"E15431-004"
LOCATION"C2A12"
PART_NUMBER"602433-106"
PACK_TYPE"0603V"
MATERIAL"X5R"
TOLERANCE"20%"
VOLTAGE"4V"
VALUE"47UF"
GROUP"PWR_MLCC_CAP"
CDS_LIB"dev_discrete"
SEC"1"
SEC_TYPE"0603V"
CDS_SEC"1"
CDS_LOCATION"C2A12";
"B"
$PN"2"13;
"A"
$PN"1"12;
%"CAP_A"
"1","(1850,-75)","0","dev_discrete","I282";
;
BOM_SS"E15431-004"
MATERIAL"X5R"
VALUE"47UF"
TOLERANCE"20%"
PART_NUMBER"602433-106"
PACK_TYPE"0603V"
LOCATION"C2A1"
VOLTAGE"4V"
GROUP"PWR_MLCC_CAP"
CDS_SEC"1"
SEC_TYPE"0603V"
SEC"1"
CDS_LIB"dev_discrete"
CDS_LOCATION"C2A1";
"B"
$PN"2"13;
"A"
$PN"1"12;
%"CAP_A"
"1","(2125,-75)","0","dev_discrete","I283";
;
BOM_SS"E15431-004"
VALUE"47UF"
VOLTAGE"4V"
LOCATION"C2A2"
PART_NUMBER"602433-106"
TOLERANCE"20%"
MATERIAL"X5R"
PACK_TYPE"0603V"
GROUP"PWR_MLCC_CAP"
CDS_LIB"dev_discrete"
SEC"1"
SEC_TYPE"0603V"
CDS_SEC"1"
CDS_LOCATION"C2A2";
"B"
$PN"2"13;
"A"
$PN"1"12;
%"CAP_A"
"1","(-2225,-775)","0","dev_discrete","I284";
;
BOM_SS"E15431-004"
PART_NUMBER"602433-106"
PACK_TYPE"0603V"
MATERIAL"X5R"
LOCATION"C8M1"
TOLERANCE"20%"
VALUE"47UF"
VOLTAGE"4V"
GROUP"PWR_MLCC_CAP"
CDS_SEC"1"
SEC_TYPE"0603V"
SEC"1"
CDS_LIB"dev_discrete"
CDS_LOCATION"C8M1";
"B"
$PN"2"15;
"A"
$PN"1"14;
%"CAP_A"
"1","(-1925,-775)","0","dev_discrete","I285";
;
BOM_SS"E15431-004"
MATERIAL"X5R"
PACK_TYPE"0603V"
PART_NUMBER"602433-106"
TOLERANCE"20%"
VOLTAGE"4V"
VALUE"47UF"
LOCATION"C8L5"
GROUP"PWR_MLCC_CAP"
CDS_LIB"dev_discrete"
SEC"1"
SEC_TYPE"0603V"
CDS_SEC"1"
CDS_LOCATION"C8L5";
"B"
$PN"2"15;
"A"
$PN"1"14;
%"CAP_A"
"1","(-1625,-775)","0","dev_discrete","I286";
;
BOM_SS"E15431-004"
LOCATION"C8L6"
VALUE"47UF"
MATERIAL"X5R"
PART_NUMBER"602433-106"
VOLTAGE"4V"
PACK_TYPE"0603V"
TOLERANCE"20%"
GROUP"PWR_MLCC_CAP"
CDS_SEC"1"
SEC_TYPE"0603V"
SEC"1"
CDS_LIB"dev_discrete"
CDS_LOCATION"C8L6";
"B"
$PN"2"15;
"A"
$PN"1"14;
%"CAP_A"
"1","(-1350,-775)","0","dev_discrete","I287";
;
BOM_SS"E15431-004"
PART_NUMBER"602433-106"
VOLTAGE"4V"
MATERIAL"X5R"
PACK_TYPE"0603V"
VALUE"47UF"
LOCATION"C8L7"
TOLERANCE"20%"
GROUP"PWR_MLCC_CAP"
CDS_LIB"dev_discrete"
SEC"1"
SEC_TYPE"0603V"
CDS_SEC"1"
CDS_LOCATION"C8L7";
"B"
$PN"2"15;
"A"
$PN"1"14;
%"CAP_A"
"1","(-1075,-775)","0","dev_discrete","I288";
;
BOM_SS"E15431-004"
LOCATION"C7L4"
VALUE"47UF"
PART_NUMBER"602433-106"
GROUP"PWR_MLCC_CAP"
VOLTAGE"4V"
PACK_TYPE"0603V"
MATERIAL"X5R"
TOLERANCE"20%"
CDS_SEC"1"
SEC_TYPE"0603V"
SEC"1"
CDS_LIB"dev_discrete"
CDS_LOCATION"C7L4";
"B"
$PN"2"15;
"A"
$PN"1"14;
%"CAP_A"
"1","(-775,-775)","0","dev_discrete","I289";
;
BOM_SS"E15431-004"
LOCATION"C8L8"
MATERIAL"X5R"
PACK_TYPE"0603V"
VALUE"47UF"
PART_NUMBER"602433-106"
VOLTAGE"4V"
TOLERANCE"20%"
GROUP"PWR_MLCC_CAP"
CDS_LIB"dev_discrete"
SEC"1"
SEC_TYPE"0603V"
CDS_SEC"1"
CDS_LOCATION"C8L8";
"B"
$PN"2"15;
"A"
$PN"1"14;
%"CAP_A"
"1","(-475,-775)","0","dev_discrete","I290";
;
BOM_SS"E15431-004"
VOLTAGE"4V"
TOLERANCE"20%"
GROUP"PWR_MLCC_CAP"
PACK_TYPE"0603V"
PART_NUMBER"602433-106"
VALUE"47UF"
MATERIAL"X5R"
LOCATION"C8L9"
CDS_SEC"1"
SEC_TYPE"0603V"
SEC"1"
CDS_LIB"dev_discrete"
CDS_LOCATION"C8L9";
"B"
$PN"2"15;
"A"
$PN"1"14;
%"CAP_A"
"1","(-200,-775)","0","dev_discrete","I291";
;
BOM_SS"E15431-004"
VOLTAGE"4V"
TOLERANCE"20%"
MATERIAL"X5R"
PART_NUMBER"602433-106"
PACK_TYPE"0603V"
GROUP"PWR_MLCC_CAP"
LOCATION"C8M6"
VALUE"47UF"
CDS_LIB"dev_discrete"
SEC"1"
SEC_TYPE"0603V"
CDS_SEC"1"
CDS_LOCATION"C8M6";
"B"
$PN"2"15;
"A"
$PN"1"14;
%"CAP_A"
"1","(125,-775)","0","dev_discrete","I292";
;
BOM_SS"E15431-004"
TOLERANCE"20%"
VALUE"47UF"
PACK_TYPE"0603V"
MATERIAL"X5R"
PART_NUMBER"602433-106"
VOLTAGE"4V"
LOCATION"C2A4"
GROUP"PWR_MLCC_CAP"
CDS_SEC"1"
SEC_TYPE"0603V"
SEC"1"
CDS_LIB"dev_discrete"
CDS_LOCATION"C2A4";
"B"
$PN"2"15;
"A"
$PN"1"14;
%"CAP_A"
"1","(425,-775)","0","dev_discrete","I293";
;
BOM_SS"E15431-004"
TOLERANCE"20%"
PACK_TYPE"0603V"
VOLTAGE"4V"
PART_NUMBER"602433-106"
MATERIAL"X5R"
VALUE"47UF"
LOCATION"C8M4"
GROUP"PWR_MLCC_CAP"
CDS_LIB"dev_discrete"
SEC"1"
SEC_TYPE"0603V"
CDS_SEC"1"
CDS_LOCATION"C8M4";
"B"
$PN"2"15;
"A"
$PN"1"14;
%"CAP_A"
"1","(725,-775)","0","dev_discrete","I294";
;
BOM_SS"E15431-004"
MATERIAL"X5R"
PACK_TYPE"0603V"
TOLERANCE"20%"
VOLTAGE"4V"
VALUE"47UF"
LOCATION"C7M2"
PART_NUMBER"602433-106"
GROUP"PWR_MLCC_CAP"
CDS_SEC"1"
SEC_TYPE"0603V"
SEC"1"
CDS_LIB"dev_discrete"
CDS_LOCATION"C7M2";
"B"
$PN"2"15;
"A"
$PN"1"14;
%"CAP_A"
"1","(1000,-775)","0","dev_discrete","I295";
;
BOM_SS"E15431-004"
MATERIAL"X5R"
PACK_TYPE"0603V"
TOLERANCE"20%"
VALUE"47UF"
VOLTAGE"4V"
PART_NUMBER"602433-106"
LOCATION"C7M1"
GROUP"PWR_MLCC_CAP"
CDS_LIB"dev_discrete"
SEC"1"
SEC_TYPE"0603V"
CDS_SEC"1"
CDS_LOCATION"C7M1";
"B"
$PN"2"15;
"A"
$PN"1"14;
%"CAP_A"
"1","(1275,-775)","0","dev_discrete","I296";
;
BOM_SS"E15431-004"
MATERIAL"X5R"
VOLTAGE"4V"
PART_NUMBER"602433-106"
VALUE"47UF"
LOCATION"C2A3"
PACK_TYPE"0603V"
TOLERANCE"20%"
GROUP"PWR_MLCC_CAP"
CDS_SEC"1"
SEC_TYPE"0603V"
SEC"1"
CDS_LIB"dev_discrete"
CDS_LOCATION"C2A3";
"B"
$PN"2"15;
"A"
$PN"1"14;
%"CAP_A"
"1","(1575,-775)","0","dev_discrete","I297";
;
BOM_SS"E15431-004"
MATERIAL"X5R"
TOLERANCE"20%"
PACK_TYPE"0603V"
VALUE"47UF"
PART_NUMBER"602433-106"
LOCATION"C8L10"
VOLTAGE"4V"
GROUP"PWR_MLCC_CAP"
CDS_LIB"dev_discrete"
SEC"1"
SEC_TYPE"0603V"
CDS_SEC"1"
CDS_LOCATION"C8L10";
"B"
$PN"2"15;
"A"
$PN"1"14;
%"CAP_A"
"1","(1875,-775)","0","dev_discrete","I298";
;
BOM_SS"E15431-004"
MATERIAL"X5R"
VOLTAGE"4V"
PART_NUMBER"602433-106"
VALUE"47UF"
PACK_TYPE"0603V"
TOLERANCE"20%"
LOCATION"C8M5"
GROUP"PWR_MLCC_CAP"
CDS_SEC"1"
SEC_TYPE"0603V"
SEC"1"
CDS_LIB"dev_discrete"
CDS_LOCATION"C8M5";
"B"
$PN"2"15;
"A"
$PN"1"14;
%"CAP_A"
"1","(2150,-775)","0","dev_discrete","I299";
;
MATERIAL"X5R"
BOM_SS"E15431-004"
VOLTAGE"4V"
LOCATION"C8M3"
VALUE"47UF"
PACK_TYPE"0603V"
PART_NUMBER"602433-106"
TOLERANCE"20%"
GROUP"PWR_MLCC_CAP"
CDS_SEC"1"
SEC_TYPE"0603V"
SEC"1"
CDS_LIB"dev_discrete"
CDS_LOCATION"C8M3";
"B"
$PN"2"15;
"A"
$PN"1"14;
%"CAP"
"1","(2400,2825)","0","mstr_discrete","I301";
;
LOCATION"C8L1"
VALUE"100UF"
VOLTAGE"4V"
TOLERANCE"20%"
PART_NUMBER"602433-112"
PACK_TYPE"0805"
NEW_MATERIAL"X6S"
BOM_SS"NOPOP"
GROUP"PWR_MLCC_CAP"
NEW_PN"078.1071T.M002"
CDS_LOCATION"C8L1"
MATERIAL"X5R"
SEC"1"
SEC_TYPE"0805"
ROOM"VDDQ_ABC_PWR_VR"
BOM_COST"MEM_VRD_PVDDQ_CD"
CDS_LIB"mstr_discrete"
CDS_SEC"1";
"A"
$PN"1"26;
"B"
$PN"2"27;
%"CAP"
"1","(4250,2825)","0","mstr_discrete","I302";
;
LOCATION"C8L11"
VALUE"100UF"
VOLTAGE"4V"
TOLERANCE"20%"
PACK_TYPE"0805"
PART_NUMBER"602433-112"
BOM_SS"NOPOP"
NEW_MATERIAL"X6S"
GROUP"PWR_MLCC_CAP"
NEW_PN"078.1071T.M002"
CDS_LOCATION"C8L11"
CDS_SEC"1"
CDS_LIB"mstr_discrete"
BOM_COST"MEM_VRD_PVDDQ_CD"
ROOM"VDDQ_ABC_PWR_VR"
SEC_TYPE"0805"
SEC"1"
MATERIAL"X5R";
"A"
$PN"1"26;
"B"
$PN"2"27;
%"CAP"
"1","(-2325,2975)","0","mstr_discrete","I303";
;
LOCATION"C8P2"
PACK_TYPE"0805"
VALUE"100UF"
VOLTAGE"4V"
TOLERANCE"20%"
BOM_SS"NOPOP"
PART_NUMBER"602433-112"
GROUP"PWR_MLCC_CAP"
NEW_MATERIAL"X6S"
NEW_PN"078.1071T.M002"
CDS_LOCATION"C8P2"
MATERIAL"X5R"
SEC"1"
SEC_TYPE"0805"
ROOM"VDDQ_ABC_PWR_VR"
BOM_COST"MEM_VRD_PVDDQ_CD"
CDS_LIB"mstr_discrete"
CDS_SEC"1";
"A"
$PN"1"7;
"B"
$PN"2"11;
%"CAP"
"1","(-1925,2975)","0","mstr_discrete","I304";
;
LOCATION"C8P1"
VOLTAGE"4V"
BOM_SS"NOPOP"
GROUP"PWR_MLCC_CAP"
NEW_MATERIAL"X6S"
PACK_TYPE"0805"
PART_NUMBER"602433-112"
TOLERANCE"20%"
VALUE"100UF"
NEW_PN"078.1071T.M002"
CDS_LOCATION"C8P1"
CDS_SEC"1"
CDS_LIB"mstr_discrete"
BOM_COST"MEM_VRD_PVDDQ_CD"
ROOM"VDDQ_ABC_PWR_VR"
SEC_TYPE"0805"
SEC"1"
MATERIAL"X5R";
"A"
$PN"1"7;
"B"
$PN"2"11;
%"CAP"
"1","(1625,2775)","0","mstr_discrete","I305";
;
LOCATION"C7P2"
TOLERANCE"20%"
VOLTAGE"4V"
VALUE"100UF"
NEW_MATERIAL"X6S"
PACK_TYPE"0805"
PART_NUMBER"602433-112"
BOM_SS"NOPOP"
GROUP"PWR_MLCC_CAP"
NEW_PN"078.1071T.M002"
CDS_LOCATION"C7P2"
CDS_SEC"1"
CDS_LIB"mstr_discrete"
BOM_COST"MEM_VRD_PVDDQ_CD"
ROOM"VDDQ_ABC_PWR_VR"
SEC_TYPE"0805"
SEC"1"
MATERIAL"X5R";
"A"
$PN"1"16;
"B"
$PN"2"17;
%"CAP"
"1","(1125,2775)","0","mstr_discrete","I306";
;
CDS_SEC"1"
CDS_LOCATION"C8P3"
LOCATION"C8P3"
VALUE"100UF"
VOLTAGE"4V"
PACK_TYPE"0805"
PART_NUMBER"602433-112"
BOM_SS"NOPOP"
GROUP"PWR_MLCC_CAP"
NEW_MATERIAL"X6S"
NEW_PN"078.1071T.M002"
TOLERANCE"20%"
CDS_LIB"mstr_discrete"
MATERIAL"X5R"
ROOM"VDDQ_ABC_PWR_VR"
BOM_COST"MEM_VRD_PVDDQ_CD"
SEC_TYPE"0805"
SEC"1";
"A"
$PN"1"16;
"B"
$PN"2"17;
%"CAP"
"1","(650,2775)","0","mstr_discrete","I307";
;
CDS_SEC"1"
CDS_LOCATION"C8P4"
TOLERANCE"20%"
VOLTAGE"4V"
VALUE"100UF"
LOCATION"C8P4"
PACK_TYPE"0805"
PART_NUMBER"602433-112"
BOM_SS"NOPOP"
NEW_MATERIAL"X6S"
GROUP"PWR_MLCC_CAP"
NEW_PN"078.1071T.M002"
CDS_LIB"mstr_discrete"
MATERIAL"X5R"
ROOM"VDDQ_ABC_PWR_VR"
BOM_COST"MEM_VRD_PVDDQ_CD"
SEC_TYPE"0805"
SEC"1";
"A"
$PN"1"16;
"B"
$PN"2"17;
%"CAP"
"1","(525,725)","0","mstr_discrete","I308";
;
TOLERANCE"20%"
LOCATION"C7P1"
VALUE"100UF"
BOM_SS"NOPOP"
NEW_MATERIAL"X6S"
PACK_TYPE"0805"
PART_NUMBER"602433-112"
VOLTAGE"4V"
GROUP"PWR_MLCC_CAP"
NEW_PN"078.1071T.M002"
CDS_LOCATION"C7P1"
CDS_SEC"1"
CDS_LIB"mstr_discrete"
BOM_COST"MEM_VRD_PVDDQ_CD"
ROOM"VDDQ_ABC_PWR_VR"
SEC_TYPE"0805"
SEC"1"
MATERIAL"X5R";
"A"
$PN"1"21;
"B"
$PN"2"20;
%"CAP"
"1","(4950,2825)","0","mstr_discrete","I309";
;
PACK_TYPE"0805"
VALUE"100UF"
VOLTAGE"4V"
TOLERANCE"20%"
PART_NUMBER"602433-112"
LOCATION"C2A8"
GROUP"PWR_MLCC_CAP"
BOM_SS"NOPOP"
NEW_MATERIAL"X6S"
NEW_PN"078.1071T.M002"
CDS_LOCATION"C2A8"
MATERIAL"X5R"
SEC"1"
SEC_TYPE"0805"
ROOM"VDDQ_ABC_PWR_VR"
BOM_COST"MEM_VRD_PVDDQ_CD"
CDS_LIB"mstr_discrete"
CDS_SEC"1";
"A"
$PN"1"26;
"B"
$PN"2"27;
%"CAP"
"1","(4600,2825)","0","mstr_discrete","I310";
;
LOCATION"C8L2"
PACK_TYPE"0805"
PART_NUMBER"602433-112"
TOLERANCE"20%"
BOM_SS"NOPOP"
VALUE"100UF"
VOLTAGE"4V"
NEW_PN"078.1071T.M002"
NEW_MATERIAL"X6S"
GROUP"PWR_MLCC_CAP"
CDS_LOCATION"C8L2"
MATERIAL"X5R"
SEC"1"
SEC_TYPE"0805"
ROOM"VDDQ_ABC_PWR_VR"
BOM_COST"MEM_VRD_PVDDQ_CD"
CDS_LIB"mstr_discrete"
CDS_SEC"1";
"A"
$PN"1"26;
"B"
$PN"2"27;
%"CAP"
"1","(3150,2825)","0","mstr_discrete","I311";
;
LOCATION"C8M11"
VALUE"100UF"
VOLTAGE"4V"
GROUP"PWR_MLCC_CAP"
TOLERANCE"20%"
PART_NUMBER"602433-112"
PACK_TYPE"0805"
NEW_MATERIAL"X6S"
BOM_SS"NOPOP"
NEW_PN"078.1071T.M002"
CDS_LOCATION"C8M11"
CDS_SEC"1"
CDS_LIB"mstr_discrete"
BOM_COST"MEM_VRD_PVDDQ_CD"
ROOM"VDDQ_ABC_PWR_VR"
SEC_TYPE"0805"
SEC"1"
MATERIAL"X5R";
"A"
$PN"1"26;
"B"
$PN"2"27;
%"CAP"
"1","(3500,2825)","0","mstr_discrete","I312";
;
PART_NUMBER"602433-112"
PACK_TYPE"0805"
LOCATION"C8M7"
TOLERANCE"20%"
VOLTAGE"4V"
VALUE"100UF"
NEW_MATERIAL"X6S"
BOM_SS"NOPOP"
GROUP"PWR_MLCC_CAP"
NEW_PN"078.1071T.M002"
CDS_LOCATION"C8M7"
CDS_SEC"1"
CDS_LIB"mstr_discrete"
BOM_COST"MEM_VRD_PVDDQ_CD"
ROOM"VDDQ_ABC_PWR_VR"
SEC_TYPE"0805"
SEC"1"
MATERIAL"X5R";
"A"
$PN"1"26;
"B"
$PN"2"27;
%"CAP"
"1","(3850,2825)","0","mstr_discrete","I313";
;
PART_NUMBER"602433-112"
TOLERANCE"20%"
VOLTAGE"4V"
VALUE"100UF"
LOCATION"C2A16"
GROUP"PWR_MLCC_CAP"
BOM_SS"NOPOP"
PACK_TYPE"0805"
NEW_MATERIAL"X6S"
NEW_PN"078.1071T.M002"
CDS_LOCATION"C2A16"
CDS_SEC"1"
CDS_LIB"mstr_discrete"
BOM_COST"MEM_VRD_PVDDQ_CD"
ROOM"VDDQ_ABC_PWR_VR"
SEC_TYPE"0805"
SEC"1"
MATERIAL"X5R";
"A"
$PN"1"26;
"B"
$PN"2"27;
%"CAP"
"1","(2750,2825)","0","mstr_discrete","I314";
;
PACK_TYPE"0805"
TOLERANCE"20%"
GROUP"PWR_MLCC_CAP"
BOM_SS"NOPOP"
NEW_MATERIAL"X6S"
PART_NUMBER"602433-112"
VOLTAGE"4V"
VALUE"100UF"
LOCATION"C7L1"
NEW_PN"078.1071T.M002"
CDS_LOCATION"C7L1"
MATERIAL"X5R"
SEC"1"
SEC_TYPE"0805"
ROOM"VDDQ_ABC_PWR_VR"
BOM_COST"MEM_VRD_PVDDQ_CD"
CDS_LIB"mstr_discrete"
CDS_SEC"1";
"A"
$PN"1"26;
"B"
$PN"2"27;
%"RES"
"2","(4100,-500)","0","mstr_discrete","I58";
;
LOCATION"R1A1"
VALUE"120.0"
TOLERANCE"1%"
WATTAGE"1/10W"
PART_NUMBER"G22026-003"
MATERIAL"CHIP"
PACK_TYPE"0603"
CDS_LIB"mstr_discrete"
ROOM"VDDQ_KLM_PWR_VR"
CDS_LOCATION"R1A1"
BOM_COST"MEM_VRD_PVPP_AB"
$SEC"1"
CDS_SEC"1";
"A"
$PN"1"24;
"B"
$PN"2"25;
%"GND"
"1","(275,1500)","0","mstr_symbols","I65";
;
CDS_LIB"mstr_symbols"
VOLTAGE"0"
SIZE"1B"
BOM_COST"MEM_VRD_PVPP_AB"
ROOM"VDDQ_KLM_PWR_VR"
BODY_TYPE"PLUMBING"
HDL_POWER"GND";
"A\NAC"22;
%"PVDDQ_KLM"
"1","(300,2375)","0","mstr_symbols","I73";
;
ROOM"VDDQ_KLM_PWR_VR"
BOM_COST"MEM_VRD_PVPP_AB"
CDS_LIB"mstr_symbols"
VOLTAGE"1.2V"
BODY_TYPE"PLUMBING"
HDL_POWER"PVDDQ_KLM";
"G\NAC"23;
%"RES"
"2","(-375,1925)","0","mstr_discrete","I74";
;
CDS_SEC"1"
TOLERANCE"1%"
PART_NUMBER"G21796-017"
WATTAGE"1/16W"
PACK_TYPE"0402"
MATERIAL"EMPTY"
LOCATION"R7L2"
VALUE"100.0"
SEC_TYPE"0402"
ROOM"VDDQ_KLM_PWR_VR"
SEC"1"
CDS_LOCATION"R7L2"
CDS_LIB"mstr_discrete";
"A"
$PN"1"28;
"B"
$PN"2"29;
%"CAPP"
"1","(2900,-500)","0","mstr_discrete","I75";
;
CDS_SEC"1"
PACK_TYPE"3018"
PART_NUMBER"699013-049"
MATERIAL"ALUM"
VOLTAGE"2.5V"
TOLERANCE"20%"
VALUE"470UF"
LOCATION"C9L9"
GROUP"PWR_BULK_CAP"
CDS_LIB"mstr_discrete"
CDS_LOCATION"C9L9"
ROOM"VDDQ_KLM_PWR_VR"
SEC_TYPE"3018"
SEC"1";
"B"
$PN"2"25;
"A"
$PN"1"24;
%"CAPP"
"1","(3200,-500)","0","mstr_discrete","I76";
;
CDS_SEC"1"
VOLTAGE"2.5V"
MATERIAL"ALUM"
PACK_TYPE"3018"
PART_NUMBER"699013-049"
TOLERANCE"20%"
VALUE"470UF"
LOCATION"C9L12"
GROUP"PWR_BULK_CAP"
CDS_LIB"mstr_discrete"
ROOM"VDDQ_KLM_PWR_VR"
CDS_LOCATION"C9L12"
SEC"1"
SEC_TYPE"3018";
"B"
$PN"2"25;
"A"
$PN"1"24;
%"CAPP"
"1","(3500,-500)","0","mstr_discrete","I77";
;
CDS_SEC"1"
VOLTAGE"2.5V"
TOLERANCE"20%"
VALUE"470UF"
MATERIAL"ALUM"
PACK_TYPE"3018"
PART_NUMBER"699013-049"
LOCATION"C9L4"
GROUP"PWR_BULK_CAP"
CDS_LIB"mstr_discrete"
CDS_LOCATION"C9L4"
ROOM"VDDQ_KLM_PWR_VR"
SEC_TYPE"3018"
SEC"1";
"B"
$PN"2"25;
"A"
$PN"1"24;
%"CAPP"
"1","(3800,-500)","0","mstr_discrete","I78";
;
CDS_SEC"1"
VOLTAGE"2.5V"
VALUE"470UF"
TOLERANCE"20%"
MATERIAL"ALUM"
PACK_TYPE"3018"
PART_NUMBER"699013-049"
LOCATION"C9L2"
GROUP"PWR_BULK_CAP"
CDS_LIB"mstr_discrete"
CDS_LOCATION"C9L2"
ROOM"VDDQ_KLM_PWR_VR"
SEC_TYPE"3018"
SEC"1";
"B"
$PN"2"25;
"A"
$PN"1"24;
%"PVDDQ_KLM"
"1","(2900,-175)","0","mstr_symbols","I80";
;
ROOM"VDDQ_KLM_PWR_VR"
CDS_LIB"mstr_symbols"
BOM_COST"MEM_VRD_PVPP_AB"
VOLTAGE"1.2V"
BODY_TYPE"PLUMBING"
HDL_POWER"PVDDQ_KLM";
"G\NAC"24;
%"GND"
"1","(2900,-825)","0","mstr_symbols","I81";
;
CDS_LIB"mstr_symbols"
SIZE"1B"
VOLTAGE"0"
BOM_COST"MEM_VRD_PVPP_AB"
BODY_TYPE"PLUMBING"
HDL_POWER"GND";
"A\NAC"25;
%"PVDDQ_KLM"
"1","(2400,3100)","0","mstr_symbols","I93";
;
ROOM"VDDQ_KLM_PWR_VR"
CDS_LIB"mstr_symbols"
BOM_COST"MEM_VRD_PVDDQ_CD"
VOLTAGE"1.2V"
BODY_TYPE"PLUMBING"
HDL_POWER"PVDDQ_KLM";
"G\NAC"26;
%"GND"
"1","(2400,2400)","0","mstr_symbols","I94";
;
CDS_LIB"mstr_symbols"
SIZE"1B"
VOLTAGE"0"
BOM_COST"MEM_VRD_PVDDQ_CD"
ROOM"VDDQ_KLM_PWR_VR"
BODY_TYPE"PLUMBING"
HDL_POWER"GND";
"A\NAC"27;
END.
